# SCM (Grand Teton) — schematic netlist excerpt (pin names and nets, part order shuffled) for the footprints in the layout excerpt that follows; sources: Cadence DE-HDL packaged netlist, KiCad conversion of 12092022_DA0F0TMDCD0_F0T_Management_Board_D_brd_V3_OCP.brd

U35  DT1240E04LP7  DT1240E-04LP-7 IC  pkg U-DFN2510-10_0-5_2-5X1  page 23
  IO1  = V_DACB_IO
  IO2  = V_DACG_IO
  VSS1  = GND
  IO3  = V_DACR_IO
  IO4  = TP4
  NC1  = TP_ESD_VGA_P4
  NC2  = V_DACR_IO
  VSS2  = GND
  NC3  = V_DACG_IO
  NC4  = V_DACB_IO

U55  SN74LVC1G14DCKR  IC  pkg SMLF  page 25
  NC  = NC_U55_P1
  A  = FLASH_LATCH_Q_N_R2
  GND  = GND
  Y  = FLASH_R_WP_STATUS
  VCC  = P3V3_AUX

(kicad_pcb
	(version 20260206)
	(generator "pcbnew")
	(generator_version "10.0")
	(general
		(thickness 1.6)
		(legacy_teardrops no)
	)
	(paper "A4")
	(title_block
		(title "12092022_DA0F0TMDCD0_F0T_Management_Board_D_brd_V3_OCP.brd")
		(comment 1 "Grand Teton / footprints 481-482 of 1440")
	)
	(layers
		(0 "F.Cu" signal "TOP")
		(4 "In1.Cu" signal "GND")
		(6 "In2.Cu" signal "IN1")
		(8 "In3.Cu" signal "GND1")
		(10 "In4.Cu" signal "IN2")
		(12 "In5.Cu" signal "VCC")
		(14 "In6.Cu" signal "VCC1")
		(16 "In7.Cu" signal "IN3")
		(18 "In8.Cu" signal "GND2")
		(20 "In9.Cu" signal "IN4")
		(22 "In10.Cu" signal "GND3")
		(2 "B.Cu" signal "BOTTOM")
		(9 "F.Adhes" user "F.Adhesive")
		(11 "B.Adhes" user "B.Adhesive")
		(13 "F.Paste" user "Package Geometry/Pastemask Top")
		(15 "B.Paste" user "Package Geometry/Pastemask Bottom")
		(5 "F.SilkS" user "Ref Des/Silkscreen Top")
		(7 "B.SilkS" user "Ref Des/Silkscreen Bottom")
		(1 "F.Mask" user "Board Geometry/Soldermask Top")
		(3 "B.Mask" user "Board Geometry/Soldermask Bottom")
		(17 "Dwgs.User" user "User.Drawings")
		(19 "Cmts.User" user "User.Comments")
		(21 "Eco1.User" user "User.Eco1")
		(23 "Eco2.User" user "User.Eco2")
		(25 "Edge.Cuts" user "Board Geometry/Outline")
		(27 "Margin" user)
		(31 "F.CrtYd" user "Package Geometry/Place Bound Top")
		(29 "B.CrtYd" user "Package Geometry/Place Bound Bottom")
		(35 "F.Fab" user "Ref Des/Assembly Top")
		(33 "B.Fab" user "Ref Des/Assembly Bottom")
	)
	(footprint ""
		(layer "F.Cu")
		(at 31.75 -31.115 180)
		(property "Reference" "U35"
			(at 1.016 3.30073 0)
			(unlocked yes)
			(layer "F.SilkS")
			(effects
				(font
					(size 0.7874 0.5842)
					(thickness 0.1524)
				)
				(justify left)
			)
		)
		(property "Value" ""
			(at 0 0 180)
			(layer "F.Fab")
			(effects
				(font
					(size 1.27 1.27)
				)
			)
		)
		(duplicate_pad_numbers_are_jumpers no)
		(fp_line
			(start 0.791464 1.287526)
			(end 0.791464 -1.287526)
			(stroke
				(width 0.1524)
				(type default)
			)
			(layer "F.SilkS")
		)
		(fp_line
			(start 0.791464 -1.287526)
			(end -0.791464 -1.287526)
			(stroke
				(width 0.1524)
				(type default)
			)
			(layer "F.SilkS")
		)
		(fp_line
			(start -0.791464 1.287526)
			(end 0.791464 1.287526)
			(stroke
				(width 0.1524)
				(type default)
			)
			(layer "F.SilkS")
		)
		(fp_line
			(start -0.791464 -1.287526)
			(end -0.791464 1.287526)
			(stroke
				(width 0.1524)
				(type default)
			)
			(layer "F.SilkS")
		)
		(fp_poly
			(pts
				(xy -1.651 -1.253998) (xy -1.651 -0.745998) (xy -1.143 -0.999998)
			)
			(stroke
				(width 0)
				(type default)
			)
			(fill yes)
			(layer "F.SilkS")
		)
		(fp_line
			(start 0.537464 1.287526)
			(end 0.537464 -1.287526)
			(stroke
				(width 0.1)
				(type default)
			)
			(layer "F.Fab")
		)
		(fp_line
			(start 0.537464 -1.287526)
			(end -0.537464 -1.287526)
			(stroke
				(width 0.1)
				(type default)
			)
			(layer "F.Fab")
		)
		(fp_line
			(start -0.537464 1.287526)
			(end 0.537464 1.287526)
			(stroke
				(width 0.1)
				(type default)
			)
			(layer "F.Fab")
		)
		(fp_line
			(start -0.537464 -1.287526)
			(end -0.537464 1.287526)
			(stroke
				(width 0.1)
				(type default)
			)
			(layer "F.Fab")
		)
		(fp_poly
			(pts
				(xy -1.651 -1.253998) (xy -1.651 -0.745998) (xy -1.143 -0.999998)
			)
			(stroke
				(width 0)
				(type default)
			)
			(fill yes)
			(layer "F.Fab")
		)
		(pad "1" smd rect
			(at -0.387604 -0.999998 270)
			(size 0.254 0.635)
			(layers "F.Cu" "F.Mask" "F.Paste")
			(net "V_DACB_IO")
		)
		(pad "2" smd rect
			(at -0.387604 -0.499872 270)
			(size 0.254 0.635)
			(layers "F.Cu" "F.Mask" "F.Paste")
			(net "V_DACG_IO")
		)
		(pad "3" smd rect
			(at -0.350012 0 270)
			(size 0.4572 0.6858)
			(layers "F.Cu" "F.Mask" "F.Paste")
			(net "GND")
		)
		(pad "4" smd rect
			(at -0.387604 0.499872 270)
			(size 0.254 0.635)
			(layers "F.Cu" "F.Mask" "F.Paste")
			(net "V_DACR_IO")
		)
		(pad "5" smd rect
			(at -0.387604 0.999998 270)
			(size 0.254 0.635)
			(layers "F.Cu" "F.Mask" "F.Paste")
			(net "TP4")
		)
		(pad "6" smd rect
			(at 0.387604 0.999998 270)
			(size 0.254 0.635)
			(layers "F.Cu" "F.Mask" "F.Paste")
			(net "TP_ESD_VGA_P4")
		)
		(pad "7" smd rect
			(at 0.387604 0.499872 270)
			(size 0.254 0.635)
			(layers "F.Cu" "F.Mask" "F.Paste")
			(net "V_DACR_IO")
		)
		(pad "8" smd rect
			(at 0.412496 0 270)
			(size 0.4572 0.5842)
			(layers "F.Cu" "F.Mask" "F.Paste")
			(net "GND")
		)
		(pad "9" smd rect
			(at 0.387604 -0.499872 270)
			(size 0.254 0.635)
			(layers "F.Cu" "F.Mask" "F.Paste")
			(net "V_DACG_IO")
		)
		(pad "10" smd rect
			(at 0.387604 -0.999998 270)
			(size 0.254 0.635)
			(layers "F.Cu" "F.Mask" "F.Paste")
			(net "V_DACB_IO")
		)
	)
	(footprint ""
		(layer "F.Cu")
		(at 52.578 -79.6544 180)
		(property "Reference" "U55"
			(at 2.8448 1.54813 0)
			(unlocked yes)
			(layer "F.SilkS")
			(effects
				(font
					(size 0.7874 0.5842)
					(thickness 0.1524)
				)
			)
		)
		(property "Value" ""
			(at 0 0 180)
			(layer "F.Fab")
			(effects
				(font
					(size 1.27 1.27)
				)
			)
		)
		(duplicate_pad_numbers_are_jumpers no)
		(fp_line
			(start 1.7018 1.1176)
			(end -1.7018 1.1176)
			(stroke
				(width 0.1524)
				(type default)
			)
			(layer "F.SilkS")
		)
		(fp_line
			(start 1.7018 -1.1176)
			(end 1.7018 1.1176)
			(stroke
				(width 0.1524)
				(type default)
			)
			(layer "F.SilkS")
		)
		(fp_line
			(start 1.7018 -1.1176)
			(end 0.254 -1.1176)
			(stroke
				(width 0.1524)
				(type default)
			)
			(layer "F.SilkS")
		)
		(fp_line
			(start 0.254 -1.1176)
			(end 0 -0.7112)
			(stroke
				(width 0.1524)
				(type default)
			)
			(layer "F.SilkS")
		)
		(fp_line
			(start 0 -0.7112)
			(end -0.254 -1.1176)
			(stroke
				(width 0.1524)
				(type default)
			)
			(layer "F.SilkS")
		)
		(fp_line
			(start -0.254 -1.1176)
			(end -1.7018 -1.1176)
			(stroke
				(width 0.1524)
				(type default)
			)
			(layer "F.SilkS")
		)
		(fp_line
			(start -1.7018 1.1176)
			(end -1.7018 -1.1176)
			(stroke
				(width 0.1524)
				(type default)
			)
			(layer "F.SilkS")
		)
		(fp_poly
			(pts
				(xy -1.8161 -0.675386) (xy -2.4003 -0.446786) (xy -2.4003 -0.878586)
			)
			(stroke
				(width 0)
				(type default)
			)
			(fill yes)
			(layer "F.SilkS")
		)
		(fp_line
			(start 1.5494 1.1176)
			(end -1.5494 1.1176)
			(stroke
				(width 0.1)
				(type default)
			)
			(layer "F.Fab")
		)
		(fp_line
			(start 1.5494 -1.1176)
			(end 1.5494 1.1176)
			(stroke
				(width 0.1)
				(type default)
			)
			(layer "F.Fab")
		)
		(fp_line
			(start 1.5494 -1.1176)
			(end 0.254 -1.1176)
			(stroke
				(width 0.1)
				(type default)
			)
			(layer "F.Fab")
		)
		(fp_line
			(start 0.254 -1.1176)
			(end -0.254 -1.1176)
			(stroke
				(width 0.1)
				(type default)
			)
			(layer "F.Fab")
		)
		(fp_line
			(start -0.254 -1.1176)
			(end -1.5494 -1.1176)
			(stroke
				(width 0.1)
				(type default)
			)
			(layer "F.Fab")
		)
		(fp_line
			(start -1.5494 1.1176)
			(end -1.5494 -1.1176)
			(stroke
				(width 0.1)
				(type default)
			)
			(layer "F.Fab")
		)
		(fp_poly
			(pts
				(xy -1.8161 -0.675386) (xy -2.4003 -0.446786) (xy -2.4003 -0.878586)
			)
			(stroke
				(width 0)
				(type default)
			)
			(fill yes)
			(layer "F.Fab")
		)
		(pad "1" smd rect
			(at -0.962406 -0.649986 90)
			(size 0.3302 1.1684)
			(layers "F.Cu" "F.Mask" "F.Paste")
			(net "NC_U55_P1")
		)
		(pad "2" smd rect
			(at -0.962406 0 90)
			(size 0.3302 1.1684)
			(layers "F.Cu" "F.Mask" "F.Paste")
			(net "FLASH_LATCH_Q_N_R2")
		)
		(pad "3" smd rect
			(at -0.962406 0.649986 90)
			(size 0.3302 1.1684)
			(layers "F.Cu" "F.Mask" "F.Paste")
			(net "GND")
		)
		(pad "4" smd rect
			(at 0.962406 0.649986 90)
			(size 0.3302 1.1684)
			(layers "F.Cu" "F.Mask" "F.Paste")
			(net "FLASH_R_WP_STATUS")
		)
		(pad "5" smd rect
			(at 0.962406 -0.649986 90)
			(size 0.3302 1.1684)
			(layers "F.Cu" "F.Mask" "F.Paste")
			(net "P3V3_AUX")
		)
	)
)
